(kicad_pcb
	(version 20260206)
	(generator "pcbnew")
	(generator_version "10.0")
	(general
		(thickness 1.6)
		(legacy_teardrops no)
	)
	(paper "A4")
	(title_block
		(title "15969-1a.1015WZS0858.brd")
		(comment 1 "Tioga Pass / footprints 166-168 of 295")
	)
	(layers
		(0 "F.Cu" signal "TOP")
		(4 "In1.Cu" signal "L2GND")
		(6 "In2.Cu" signal "L3")
		(8 "In3.Cu" signal "L4")
		(10 "In4.Cu" signal "L5GND")
		(2 "B.Cu" signal "BOTTOM")
		(9 "F.Adhes" user "F.Adhesive")
		(11 "B.Adhes" user "B.Adhesive")
		(13 "F.Paste" user "Package Geometry/Pastemask Top")
		(15 "B.Paste" user "Package Geometry/Pastemask Bottom")
		(5 "F.SilkS" user "Ref Des/Silkscreen Top")
		(7 "B.SilkS" user "Ref Des/Silkscreen Bottom")
		(1 "F.Mask" user "Board Geometry/Soldermask Top")
		(3 "B.Mask" user "Board Geometry/Soldermask Bottom")
		(17 "Dwgs.User" user "User.Drawings")
		(19 "Cmts.User" user "User.Comments")
		(21 "Eco1.User" user "User.Eco1")
		(23 "Eco2.User" user "User.Eco2")
		(25 "Edge.Cuts" user "Board Geometry/Outline")
		(27 "Margin" user)
		(31 "F.CrtYd" user "Package Geometry/Place Bound Top")
		(29 "B.CrtYd" user "Package Geometry/Place Bound Bottom")
		(35 "F.Fab" user "Ref Des/Assembly Top")
		(33 "B.Fab" user "Ref Des/Assembly Bottom")
	)
	(footprint ""
		(layer "F.Cu")
		(at 106.5784 0.3048)
		(property "Reference" "R16"
			(at 0 0 0)
			(layer "F.SilkS")
			(hide yes)
			(effects
				(font
					(size 1.27 1.27)
				)
			)
		)
		(property "Value" "10KR2F-2-GP"
			(at 0.064008 -3.993896 0)
			(unlocked yes)
			(layer "F.Fab")
			(hide yes)
			(effects
				(font
					(size 1.016 1.016)
					(thickness 0.1524)
				)
			)
		)
		(property "Device Type" "R402H16"
			(at 0.064008 -5.517896 0)
			(unlocked yes)
			(layer "F.Fab")
			(hide yes)
			(effects
				(font
					(size 1.016 1.016)
					(thickness 0.1524)
				)
			)
		)
		(duplicate_pad_numbers_are_jumpers no)
		(fp_line
			(start -0.508 -0.9398)
			(end -0.508 0.9398)
			(stroke
				(width 0.1524)
				(type default)
			)
			(layer "F.SilkS")
		)
		(fp_line
			(start 0.508 -0.9398)
			(end -0.508 -0.9398)
			(stroke
				(width 0.1524)
				(type default)
			)
			(layer "F.SilkS")
		)
		(fp_rect
			(start -0.508 0.9398)
			(end 0.508 -0.9398)
			(stroke
				(width 0)
				(type default)
			)
			(fill no)
			(layer "F.CrtYd")
		)
		(fp_rect
			(start -0.508 0.9398)
			(end 0.508 -0.9398)
			(stroke
				(width 0)
				(type default)
			)
			(fill no)
			(layer "F.Fab")
		)
		(pad "1" smd custom
			(at 0 -0.4445)
			(size 0.1397 0.1397)
			(layers "F.Cu" "F.Mask" "F.Paste")
			(net "P3V3_STBY")
			(options
				(clearance outline)
				(anchor circle)
			)
			(primitives
				(gr_poly
					(pts
						(arc
							(start -0.1778 -0.2794)
							(mid -0.249642 -0.249642)
							(end -0.2794 -0.1778)
						)
						(arc
							(start -0.2794 0.1778)
							(mid -0.249642 0.249642)
							(end -0.1778 0.2794)
						)
						(arc
							(start 0.1778 0.2794)
							(mid 0.249642 0.249642)
							(end 0.2794 0.1778)
						)
						(arc
							(start 0.2794 -0.1778)
							(mid 0.249642 -0.249642)
							(end 0.1778 -0.2794)
						)
					)
					(width 0)
					(fill yes)
				)
			)
		)
		(pad "2" smd custom
			(at 0 0.4445)
			(size 0.1397 0.1397)
			(layers "F.Cu" "F.Mask" "F.Paste")
			(net "SMB_B_HUB_A2")
			(options
				(clearance outline)
				(anchor circle)
			)
			(primitives
				(gr_poly
					(pts
						(arc
							(start -0.1778 -0.2794)
							(mid -0.249642 -0.249642)
							(end -0.2794 -0.1778)
						)
						(arc
							(start -0.2794 0.1778)
							(mid -0.249642 0.249642)
							(end -0.1778 0.2794)
						)
						(arc
							(start 0.1778 0.2794)
							(mid 0.249642 0.249642)
							(end 0.2794 0.1778)
						)
						(arc
							(start 0.2794 -0.1778)
							(mid 0.249642 -0.249642)
							(end 0.1778 -0.2794)
						)
					)
					(width 0)
					(fill yes)
				)
			)
		)
	)
	(footprint ""
		(layer "F.Cu")
		(at 120.57507 13.530072)
		(property "Reference" "GF1"
			(at 0 0 0)
			(layer "F.SilkS")
			(hide yes)
			(effects
				(font
					(size 1.27 1.27)
				)
			)
		)
		(property "Value" "GF-HSEC8-60P-5-GP"
			(at -15.0622 -0.8382 0)
			(unlocked yes)
			(layer "F.Fab")
			(hide yes)
			(effects
				(font
					(size 1.016 1.016)
					(thickness 0.1524)
				)
			)
		)
		(property "Device Type" "GF-HSEC8-60P"
			(at -15.0622 -2.3622 0)
			(unlocked yes)
			(layer "F.Fab")
			(hide yes)
			(effects
				(font
					(size 1.016 1.016)
					(thickness 0.1524)
				)
			)
		)
		(duplicate_pad_numbers_are_jumpers no)
		(fp_rect
			(start -13.9192 2.032)
			(end 13.9192 -4.6228)
			(stroke
				(width 0)
				(type default)
			)
			(fill no)
			(layer "B.CrtYd")
		)
		(fp_rect
			(start -13.9192 2.032)
			(end 13.9192 -4.6228)
			(stroke
				(width 0)
				(type default)
			)
			(fill no)
			(layer "F.CrtYd")
		)
		(fp_rect
			(start -13.9192 2.032)
			(end 13.9192 -4.6228)
			(stroke
				(width 0)
				(type default)
			)
			(fill no)
			(layer "B.Fab")
		)
		(fp_rect
			(start -13.9192 2.032)
			(end 13.9192 -4.6228)
			(stroke
				(width 0)
				(type default)
			)
			(fill no)
			(layer "F.Fab")
		)
		(fp_text user "02 Do not mirror"
			(at -7.62 4.1148 0)
			(unlocked yes)
			(layer "F.Fab")
			(effects
				(font
					(size 1.016 1.016)
					(thickness 0.1524)
				)
				(justify left)
			)
		)
		(pad "1" smd rect
			(at -11.599926 -1.2954)
			(size 0.5588 2.5908)
			(layers "F.Cu" "F.Mask" "F.Paste")
			(net "GND")
		)
		(pad "2" smd rect
			(at -11.599926 -0.9144)
			(size 0.5588 2.5908)
			(drill
				(offset 0 -0.381)
			)
			(layers "F.Cu" "F.Mask" "F.Paste")
			(net "Net_361")
		)
		(pad "3" smd rect
			(at -10.80008 -1.2954)
			(size 0.5588 2.5908)
			(layers "F.Cu" "F.Mask" "F.Paste")
			(net "P3E_CPU0_PE2_SS_C_TXP<8>")
		)
		(pad "4" smd rect
			(at -10.80008 -0.9144)
			(size 0.5588 2.5908)
			(drill
				(offset 0 -0.381)
			)
			(layers "F.Cu" "F.Mask" "F.Paste")
			(net "GND")
		)
		(pad "5" smd rect
			(at -9.99998 -1.2954)
			(size 0.5588 2.5908)
			(layers "F.Cu" "F.Mask" "F.Paste")
			(net "P3E_CPU0_PE2_SS_C_TXN<8>")
		)
		(pad "6" smd rect
			(at -9.99998 -0.9144)
			(size 0.5588 2.5908)
			(drill
				(offset 0 -0.381)
			)
			(layers "F.Cu" "F.Mask" "F.Paste")
			(net "P3E_CPU0_PE2_SS_RXP<8>")
		)
		(pad "7" smd rect
			(at -9.19988 -1.2954)
			(size 0.5588 2.5908)
			(layers "F.Cu" "F.Mask" "F.Paste")
			(net "GND")
		)
		(pad "8" smd rect
			(at -9.19988 -0.9144)
			(size 0.5588 2.5908)
			(drill
				(offset 0 -0.381)
			)
			(layers "F.Cu" "F.Mask" "F.Paste")
			(net "P3E_CPU0_PE2_SS_RXN<8>")
		)
		(pad "9" smd rect
			(at -8.400034 -1.2954)
			(size 0.5588 2.5908)
			(layers "F.Cu" "F.Mask" "F.Paste")
			(net "P3E_CPU0_PE2_SS_C_TXP<9>")
		)
		(pad "10" smd rect
			(at -8.400034 -0.9144)
			(size 0.5588 2.5908)
			(drill
				(offset 0 -0.381)
			)
			(layers "F.Cu" "F.Mask" "F.Paste")
			(net "GND")
		)
		(pad "11" smd rect
			(at -7.599934 -1.2954)
			(size 0.5588 2.5908)
			(layers "F.Cu" "F.Mask" "F.Paste")
			(net "P3E_CPU0_PE2_SS_C_TXN<9>")
		)
		(pad "12" smd rect
			(at -7.599934 -0.9144)
			(size 0.5588 2.5908)
			(drill
				(offset 0 -0.381)
			)
			(layers "F.Cu" "F.Mask" "F.Paste")
			(net "P3E_CPU0_PE2_SS_RXP<9>")
		)
		(pad "13" smd rect
			(at -6.800088 -1.2954)
			(size 0.5588 2.5908)
			(layers "F.Cu" "F.Mask" "F.Paste")
			(net "GND")
		)
		(pad "14" smd rect
			(at -6.800088 -0.9144)
			(size 0.5588 2.5908)
			(drill
				(offset 0 -0.381)
			)
			(layers "F.Cu" "F.Mask" "F.Paste")
			(net "P3E_CPU0_PE2_SS_RXN<9>")
		)
		(pad "15" smd rect
			(at -5.999988 -1.2954)
			(size 0.5588 2.5908)
			(layers "F.Cu" "F.Mask" "F.Paste")
			(net "P3E_CPU0_PE2_SS_C_TXP<10>")
		)
		(pad "16" smd rect
			(at -5.999988 -0.9144)
			(size 0.5588 2.5908)
			(drill
				(offset 0 -0.381)
			)
			(layers "F.Cu" "F.Mask" "F.Paste")
			(net "GND")
		)
		(pad "17" smd rect
			(at -5.199888 -1.2954)
			(size 0.5588 2.5908)
			(layers "F.Cu" "F.Mask" "F.Paste")
			(net "P3E_CPU0_PE2_SS_C_TXN<10>")
		)
		(pad "18" smd rect
			(at -5.199888 -0.9144)
			(size 0.5588 2.5908)
			(drill
				(offset 0 -0.381)
			)
			(layers "F.Cu" "F.Mask" "F.Paste")
			(net "P3E_CPU0_PE2_SS_RXP<10>")
		)
		(pad "19" smd rect
			(at -4.400042 -1.2954)
			(size 0.5588 2.5908)
			(layers "F.Cu" "F.Mask" "F.Paste")
			(net "GND")
		)
		(pad "20" smd rect
			(at -4.400042 -0.9144)
			(size 0.5588 2.5908)
			(drill
				(offset 0 -0.381)
			)
			(layers "F.Cu" "F.Mask" "F.Paste")
			(net "P3E_CPU0_PE2_SS_RXN<10>")
		)
		(pad "21" smd rect
			(at -3.599942 -1.2954)
			(size 0.5588 2.5908)
			(layers "F.Cu" "F.Mask" "F.Paste")
			(net "P3E_CPU0_PE2_SS_C_TXP<11>")
		)
		(pad "22" smd rect
			(at -3.599942 -0.9144)
			(size 0.5588 2.5908)
			(drill
				(offset 0 -0.381)
			)
			(layers "F.Cu" "F.Mask" "F.Paste")
			(net "GND")
		)
		(pad "23" smd rect
			(at -2.800096 -1.2954)
			(size 0.5588 2.5908)
			(layers "F.Cu" "F.Mask" "F.Paste")
			(net "P3E_CPU0_PE2_SS_C_TXN<11>")
		)
		(pad "24" smd rect
			(at -2.800096 -0.9144)
			(size 0.5588 2.5908)
			(drill
				(offset 0 -0.381)
			)
			(layers "F.Cu" "F.Mask" "F.Paste")
			(net "P3E_CPU0_PE2_SS_RXP<11>")
		)
		(pad "25" smd rect
			(at -1.999996 -1.2954)
			(size 0.5588 2.5908)
			(layers "F.Cu" "F.Mask" "F.Paste")
			(net "GND")
		)
		(pad "26" smd rect
			(at -1.999996 -0.9144)
			(size 0.5588 2.5908)
			(drill
				(offset 0 -0.381)
			)
			(layers "F.Cu" "F.Mask" "F.Paste")
			(net "P3E_CPU0_PE2_SS_RXN<11>")
		)
		(pad "27" smd rect
			(at -1.199896 -1.2954)
			(size 0.5588 2.5908)
			(layers "F.Cu" "F.Mask" "F.Paste")
			(net "P3E_CPU0_PE2_SS_C_TXP<12>")
		)
		(pad "28" smd rect
			(at -1.199896 -0.9144)
			(size 0.5588 2.5908)
			(drill
				(offset 0 -0.381)
			)
			(layers "F.Cu" "F.Mask" "F.Paste")
			(net "GND")
		)
		(pad "29" smd rect
			(at -0.40005 -1.2954)
			(size 0.5588 2.5908)
			(layers "F.Cu" "F.Mask" "F.Paste")
			(net "P3E_CPU0_PE2_SS_C_TXN<12>")
		)
		(pad "30" smd rect
			(at -0.40005 -0.9144)
			(size 0.5588 2.5908)
			(drill
				(offset 0 -0.381)
			)
			(layers "F.Cu" "F.Mask" "F.Paste")
			(net "P3E_CPU0_PE2_SS_RXP<12>")
		)
		(pad "31" smd rect
			(at 0.40005 -1.2954)
			(size 0.5588 2.5908)
			(layers "F.Cu" "F.Mask" "F.Paste")
			(net "GND")
		)
		(pad "32" smd rect
			(at 0.40005 -0.9144)
			(size 0.5588 2.5908)
			(drill
				(offset 0 -0.381)
			)
			(layers "F.Cu" "F.Mask" "F.Paste")
			(net "P3E_CPU0_PE2_SS_RXN<12>")
		)
		(pad "33" smd rect
			(at 1.199896 -1.2954)
			(size 0.5588 2.5908)
			(layers "F.Cu" "F.Mask" "F.Paste")
			(net "P3E_CPU0_PE2_SS_C_TXP<13>")
		)
		(pad "34" smd rect
			(at 1.199896 -0.9144)
			(size 0.5588 2.5908)
			(drill
				(offset 0 -0.381)
			)
			(layers "F.Cu" "F.Mask" "F.Paste")
			(net "GND")
		)
		(pad "35" smd rect
			(at 1.999996 -1.2954)
			(size 0.5588 2.5908)
			(layers "F.Cu" "F.Mask" "F.Paste")
			(net "P3E_CPU0_PE2_SS_C_TXN<13>")
		)
		(pad "36" smd rect
			(at 1.999996 -0.9144)
			(size 0.5588 2.5908)
			(drill
				(offset 0 -0.381)
			)
			(layers "F.Cu" "F.Mask" "F.Paste")
			(net "P3E_CPU0_PE2_SS_RXP<13>")
		)
		(pad "37" smd rect
			(at 2.800096 -1.2954)
			(size 0.5588 2.5908)
			(layers "F.Cu" "F.Mask" "F.Paste")
			(net "GND")
		)
		(pad "38" smd rect
			(at 2.800096 -0.9144)
			(size 0.5588 2.5908)
			(drill
				(offset 0 -0.381)
			)
			(layers "F.Cu" "F.Mask" "F.Paste")
			(net "P3E_CPU0_PE2_SS_RXN<13>")
		)
		(pad "39" smd rect
			(at 3.599942 -1.2954)
			(size 0.5588 2.5908)
			(layers "F.Cu" "F.Mask" "F.Paste")
			(net "P3E_CPU0_PE2_SS_C_TXP<14>")
		)
		(pad "40" smd rect
			(at 3.599942 -0.9144)
			(size 0.5588 2.5908)
			(drill
				(offset 0 -0.381)
			)
			(layers "F.Cu" "F.Mask" "F.Paste")
			(net "GND")
		)
		(pad "41" smd rect
			(at 4.400042 -1.2954)
			(size 0.5588 2.5908)
			(layers "F.Cu" "F.Mask" "F.Paste")
			(net "P3E_CPU0_PE2_SS_C_TXN<14>")
		)
		(pad "42" smd rect
			(at 4.400042 -0.9144)
			(size 0.5588 2.5908)
			(drill
				(offset 0 -0.381)
			)
			(layers "F.Cu" "F.Mask" "F.Paste")
			(net "P3E_CPU0_PE2_SS_RXP<14>")
		)
		(pad "43" smd rect
			(at 5.199888 -1.2954)
			(size 0.5588 2.5908)
			(layers "F.Cu" "F.Mask" "F.Paste")
			(net "GND")
		)
		(pad "44" smd rect
			(at 5.199888 -0.9144)
			(size 0.5588 2.5908)
			(drill
				(offset 0 -0.381)
			)
			(layers "F.Cu" "F.Mask" "F.Paste")
			(net "P3E_CPU0_PE2_SS_RXN<14>")
		)
		(pad "45" smd rect
			(at 5.999988 -1.2954)
			(size 0.5588 2.5908)
			(layers "F.Cu" "F.Mask" "F.Paste")
			(net "P3E_CPU0_PE2_SS_C_TXP<15>")
		)
		(pad "46" smd rect
			(at 5.999988 -0.9144)
			(size 0.5588 2.5908)
			(drill
				(offset 0 -0.381)
			)
			(layers "F.Cu" "F.Mask" "F.Paste")
			(net "GND")
		)
		(pad "47" smd rect
			(at 6.800088 -1.2954)
			(size 0.5588 2.5908)
			(layers "F.Cu" "F.Mask" "F.Paste")
			(net "P3E_CPU0_PE2_SS_C_TXN<15>")
		)
		(pad "48" smd rect
			(at 6.800088 -0.9144)
			(size 0.5588 2.5908)
			(drill
				(offset 0 -0.381)
			)
			(layers "F.Cu" "F.Mask" "F.Paste")
			(net "P3E_CPU0_PE2_SS_RXP<15>")
		)
		(pad "49" smd rect
			(at 7.599934 -1.2954)
			(size 0.5588 2.5908)
			(layers "F.Cu" "F.Mask" "F.Paste")
			(net "GND")
		)
		(pad "50" smd rect
			(at 7.599934 -0.9144)
			(size 0.5588 2.5908)
			(drill
				(offset 0 -0.381)
			)
			(layers "F.Cu" "F.Mask" "F.Paste")
			(net "P3E_CPU0_PE2_SS_RXN<15>")
		)
		(pad "51" smd rect
			(at 8.400034 -1.2954)
			(size 0.5588 2.5908)
			(layers "F.Cu" "F.Mask" "F.Paste")
			(net "Net_115")
		)
		(pad "52" smd rect
			(at 8.400034 -0.9144)
			(size 0.5588 2.5908)
			(drill
				(offset 0 -0.381)
			)
			(layers "F.Cu" "F.Mask" "F.Paste")
			(net "GND")
		)
		(pad "53" smd rect
			(at 9.19988 -1.2954)
			(size 0.5588 2.5908)
			(layers "F.Cu" "F.Mask" "F.Paste")
			(net "Net_114")
		)
		(pad "54" smd rect
			(at 9.19988 -0.9144)
			(size 0.5588 2.5908)
			(drill
				(offset 0 -0.381)
			)
			(layers "F.Cu" "F.Mask" "F.Paste")
			(net "Net_105")
		)
		(pad "55" smd rect
			(at 9.99998 -1.2954)
			(size 0.5588 2.5908)
			(layers "F.Cu" "F.Mask" "F.Paste")
			(net "GND")
		)
		(pad "56" smd rect
			(at 9.99998 -0.9144)
			(size 0.5588 2.5908)
			(drill
				(offset 0 -0.381)
			)
			(layers "F.Cu" "F.Mask" "F.Paste")
			(net "Net_104")
		)
		(pad "57" smd rect
			(at 10.80008 -1.2954)
			(size 0.5588 2.5908)
			(layers "F.Cu" "F.Mask" "F.Paste")
			(net "USB2_P02_DN")
		)
		(pad "58" smd rect
			(at 10.80008 -0.9144)
			(size 0.5588 2.5908)
			(drill
				(offset 0 -0.381)
			)
			(layers "F.Cu" "F.Mask" "F.Paste")
			(net "GND")
		)
		(pad "59" smd rect
			(at 11.599926 -1.2954)
			(size 0.5588 2.5908)
			(layers "F.Cu" "F.Mask" "F.Paste")
			(net "USB2_P02_DP")
		)
		(pad "60" smd rect
			(at 11.599926 -0.9144)
			(size 0.5588 2.5908)
			(drill
				(offset 0 -0.381)
			)
			(layers "F.Cu" "F.Mask" "F.Paste")
			(net "Net_360")
		)
		(zone
			(layer "F.Cu")
			(hatch none 0.5)
			(connect_pads
				(clearance 0)
			)
			(min_thickness 0.25)
			(keepout
				(tracks allowed)
				(vias not_allowed)
				(pads allowed)
				(copperpour not_allowed)
				(footprints allowed)
			)
			(placement
				(enabled no)
				(sheetname "")
			)
			(fill
				(thermal_gap 0.5)
				(thermal_bridge_width 0.5)
				(island_removal_mode 0)
			)
			(polygon
				(pts
					(xy 107.67187 14.546072) (xy 133.47827 14.546072) (xy 133.47827 9.923272) (xy 107.67187 9.923272)
				)
			)
		)
		(zone
			(layer "F.Cu")
			(hatch none 0.5)
			(connect_pads
				(clearance 0)
			)
			(min_thickness 0.25)
			(keepout
				(tracks not_allowed)
				(vias allowed)
				(pads allowed)
				(copperpour not_allowed)
				(footprints allowed)
			)
			(placement
				(enabled no)
				(sheetname "")
			)
			(fill
				(thermal_gap 0.5)
				(thermal_bridge_width 0.5)
				(island_removal_mode 0)
			)
			(polygon
				(pts
					(xy 107.67187 14.546072) (xy 133.47827 14.546072) (xy 133.47827 13.530072) (xy 107.67187 13.530072)
				)
			)
		)
		(zone
			(layer "B.Cu")
			(hatch none 0.5)
			(connect_pads
				(clearance 0)
			)
			(min_thickness 0.25)
			(keepout
				(tracks allowed)
				(vias not_allowed)
				(pads allowed)
				(copperpour not_allowed)
				(footprints allowed)
			)
			(placement
				(enabled no)
				(sheetname "")
			)
			(fill
				(thermal_gap 0.5)
				(thermal_bridge_width 0.5)
				(island_removal_mode 0)
			)
			(polygon
				(pts
					(xy 107.67187 14.546072) (xy 133.47827 14.546072) (xy 133.47827 9.923272) (xy 107.67187 9.923272)
				)
			)
		)
		(zone
			(layer "B.Cu")
			(hatch none 0.5)
			(connect_pads
				(clearance 0)
			)
			(min_thickness 0.25)
			(keepout
				(tracks not_allowed)
				(vias allowed)
				(pads allowed)
				(copperpour not_allowed)
				(footprints allowed)
			)
			(placement
				(enabled no)
				(sheetname "")
			)
			(fill
				(thermal_gap 0.5)
				(thermal_bridge_width 0.5)
				(island_removal_mode 0)
			)
			(polygon
				(pts
					(xy 107.67187 14.546072) (xy 133.47827 14.546072) (xy 133.47827 13.530072) (xy 107.67187 13.530072)
				)
			)
		)
	)
	(footprint ""
		(layer "F.Cu")
		(at 33.0581 -1.6129 -90)
		(property "Reference" "C798"
			(at 0 0 270)
			(layer "F.SilkS")
			(hide yes)
			(effects
				(font
					(size 1.27 1.27)
				)
			)
		)
		(property "Value" "SC22U6D3V5MX-5-GP"
			(at -0.0762 -6.1214 270)
			(unlocked yes)
			(layer "F.Fab")
			(hide yes)
			(effects
				(font
					(size 1.016 1.016)
					(thickness 0.1524)
				)
			)
		)
		(property "Device Type" "C805H56"
			(at -0.0762 -8.1534 270)
			(unlocked yes)
			(layer "F.Fab")
			(hide yes)
			(effects
				(font
					(size 1.016 1.016)
					(thickness 0.1524)
				)
			)
		)
		(duplicate_pad_numbers_are_jumpers no)
		(fp_line
			(start 0.635 0)
			(end -0.635 0)
			(stroke
				(width 0.508)
				(type default)
			)
			(layer "F.SilkS")
		)
		(fp_rect
			(start -0.9652 1.778)
			(end 0.9652 -1.778)
			(stroke
				(width 0)
				(type default)
			)
			(fill no)
			(layer "F.CrtYd")
		)
		(fp_poly
			(pts
				(xy -0.9652 -1.778) (xy 0.9652 -1.778) (xy 0.9652 1.778) (xy -0.9652 1.778)
			)
			(stroke
				(width 0)
				(type default)
			)
			(fill no)
			(layer "F.Fab")
		)
		(pad "1" smd rect
			(at 0 -0.9652 270)
			(size 1.397 1.143)
			(layers "F.Cu" "F.Mask" "F.Paste")
			(net "P3V3")
		)
		(pad "2" smd rect
			(at 0 0.9652 270)
			(size 1.397 1.143)
			(layers "F.Cu" "F.Mask" "F.Paste")
			(net "GND")
		)
	)
)
